FILE_TYPE = CONNECTIVITY;
{Allegro Design Entry HDL 17.2-2016 S081 (4005846) 1/11/2022}
"PAGE_NUMBER" = 22;
0"NC";
1"P3V3_AUX\g";
2"P3V3_AUX\g";
3"P3V3_AUX\g";
4"P3V3_RGM\g";
5"P3V3_AUX\g";
6"P3V3_AUX\g";
7"P3V3_AUX\g";
8"P3V3_RGM\g";
9"P3V3_AUX\g";
10"P3V3_AUX\g";
11"P3V3_AUX\g";
12"P3V3_AUX\g";
13"P1V0_AUX\g";
14"GND\g";
15"GND\g";
16"GND\g";
17"GND\g";
18"GND\g";
19"GND\g";
20"GND\g";
21"GND\g";
22"GND\g";
23"GND\g";
24"GND\g";
25"GND\g";
26"GND\g";
27"GND\g";
28"GND\g";
29"GND\g";
30"U43_CT";
31"RST_BMC_SRST_BUF_R_N";
32"RST_BMC_EXTRST_R1_N";
33"BJT_Q3_B";
34"PWRGD_P1V0_AUX_DELAY_BUF";
35"RST_SRST_PLD_BMC_BUF_N";
36"RST_SRST_PLD_BMC_R1_N";
37"PWRGD_P1V0_AUX_DELAY";
38"RST_BMC_SELF_HW";
39"RST_BMC_HW_R1";
40"RST_BMC_HW_OUT";
41"RST_BMC_SELF_HW_D_C";
42"RST_BMC_SELF_HW_D";
43"RST_BMC_HW";
44"RST_BMC_SELF_HW_R3";
45"RST_SRST_PLD_BMC_R_N";
46"PWRGD_PSU_AC_PWROK";
47"PWRGD_P1V0_AUX_DELAY_R1";
48"PWRGD_P1V0_AUX_R2";
49"BJT_Q3_C";
50"RST_EXTRST_N";
51"RST_BMC_SRST_N";
52"RST_BMC_EXTRST_R2_N";
53"PWRGD_P1V0_AUX_DELAY";
54"PWRGD_P1V0_AUX";
55"RST_BMC_SRST_N";
56"RST_BMC_SRST_BUF_R1_N";
%"Q_RES"
"1","(-2025,4200)","0","pure_quanta","I10";
;
PACK_TYPE"0402LF"
PART_NUMBER"CS00002JB13"
VALUE"0"
WATTAGE"1/16W"
MATERIAL"CHIP"
TOLERANCE"5%"
CDS_LIB"pure_quanta"
LOCATION"R636"
$SEC"1"
CDS_SEC"1";
"B"
$PN"2"52;
"A"
$PN"1"50;
%"Q_RES"
"2","(-3700,2350)","0","pure_quanta","I100";
;
MATERIAL"CHIP"
VALUE"0"
PART_NUMBER"CS00002JB13"
TOLERANCE"5%"
PACK_TYPE"0402LF"
WATTAGE"1/16W"
CDS_LIB"pure_quanta"
LOCATION"R282"
$SEC"1"
CDS_SEC"1";
"A"
$PN"1"39;
"B"
$PN"2"43;
%"Q_RES"
"2","(-3700,2750)","0","pure_quanta","I101";
;
PART_NUMBER"CS00002JB13"
VALUE"0"
MATERIAL"CHIP"
CDS_LIB"pure_quanta"
TOLERANCE"5%"
PACK_TYPE"0402LF"
WATTAGE"1/16W"
LOCATION"R450"
$SEC"1"
CDS_SEC"1";
"A"
$PN"1"38;
"B"
$PN"2"44;
%"Q_RES"
"2","(-3750,3275)","0","pure_quanta","I102";
;
PACK_TYPE"0402LF"
MATERIAL"EMPTY"
WATTAGE"1/16W"
TOLERANCE"1%"
VALUE"1K"
CDS_LIB"pure_quanta"
PART_NUMBER"CS21002FB06"
$LOCATION"R888"
CDS_LOCATION"R888"
$SEC"1"
CDS_SEC"1";
"A"
$PN"1"2;
"B"
$PN"2"38;
%"UNIVERSAL_POWER"
"1","(-3750,3475)","0","logical_power","I103";
;
HDL_POWER"P3V3_AUX"
CDS_LIB"logical_power";
"A"2;
%"UNIVERSAL_POWER"
"1","(-4000,2550)","0","logical_power","I104";
;
HDL_POWER"P3V3_AUX"
CDS_LIB"logical_power";
"A"12;
%"Q_RES"
"2","(-4000,2375)","0","pure_quanta","I106";
;
MATERIAL"EMPTY"
VALUE"4.7K"
PACK_TYPE"0402LF"
WATTAGE"1/16W"
TOLERANCE"1%"
CDS_LIB"pure_quanta"
PART_NUMBER"CS24702FB06"
$LOCATION"R887"
CDS_LOCATION"R887"
$SEC"1"
CDS_SEC"1";
"A"
$PN"1"12;
"B"
$PN"2"43;
%"Q_CAP"
"1","(325,2550)","0","pure_quanta","I107";
;
PART_NUMBER"TMP_QCH22206KB16"
TOLERANCE"10%"
MATERIAL"X7R"
PACK_TYPE"0402"
VOLTAGE"50V"
VALUE"2200PF"
CDS_LIB"pure_quanta"
LOCATION"C173"
$SEC"1"
CDS_SEC"1";
"B"
$PN"2"29;
"A"
$PN"1"41;
%"Q_RES"
"1","(-2025,3650)","0","pure_quanta","I12";
;
MATERIAL"EMPTY"
VALUE"0"
PART_NUMBER"CS00002JB13"
TOLERANCE"5%"
PACK_TYPE"0402LF"
WATTAGE"1/16W"
CDS_LIB"pure_quanta"
LOCATION"R106"
$SEC"1"
CDS_SEC"1";
"B"
$PN"2"52;
"A"
$PN"1"55;
%"MOSFET_N"
"1","(650,2875)","0","pure_quanta","I14";
;
MANUF_PN"BSS138K"
VALUE"BSS138K"
PART_NUMBER"BAM138K0000"
MATERIAL"IC"
PACK_TYPE"SMLF"
CDS_LIB"pure_quanta"
CDS_LMAN_SYM_OUTLINE"-50,50,100,-150"
LOCATION"U12"
$SEC"1"
CDS_SEC"1";
"GATE"
$PN"G"41;
"SOURCE"
$PN"S"23;
"DRAIN"
$PN"D"32;
%"UNIVERSAL_POWER"
"1","(3700,2825)","0","logical_power","I16";
;
HDL_POWER"P3V3_AUX"
CDS_LIB"logical_power";
"A"5;
%"Q_CAP"
"1","(3875,2550)","0","pure_quanta","I17";
;
PACK_TYPE"0402"
PART_NUMBER"CH4104K1B00"
VALUE"0.1UF"
TOLERANCE"10%"
VOLTAGE"25V"
MATERIAL"EMPTY"
CDS_LIB"pure_quanta"
SEC_TYPE"0402"
LOCATION"C147"
SEC"1";
"B"
$PN"2"20;
"A"
$PN"1"5;
%"UNIVERSAL_GND"
"1","(3875,2350)","0","logical_power","I18";
;
HDL_POWER"GND"
CDS_LIB"logical_power";
"A"20;
%"MMBT39047F"
"1","(-525,4025)","2","pure_quanta","I2";
;
PART_NUMBER"BA0390400H0"
VALUE"MMBT3904-7-F"
MATERIAL"IC"
PART_TYPE"SMLF"
SEC_TYPE""
CDS_LIB"pure_quanta"
NEEDS_NO_SIZE"TRUE"
CDS_LMAN_SYM_OUTLINE"-50,50,50,-50"
LOCATION"Q1"
SEC"1";
"3"
$PN"C"52;
"2"
$PN"E"17;
"1"
$PN"B"49;
%"UNIVERSAL_GND"
"1","(700,2300)","0","logical_power","I22";
;
CDS_LIB"logical_power"
HDL_POWER"GND";
"A"23;
%"Q_CAP"
"2","(-450,2775)","0","pure_quanta","I23";
;
TOLERANCE"10%"
PACK_TYPE"C0402"
PART_NUMBER"CH5104KEB02"
MATERIAL"X6S"
VOLTAGE"25V"
VALUE"1UF"
CDS_LIB"pure_quanta"
LOCATION"C161"
$SEC"1"
CDS_SEC"1";
"A"
$PN"1"42;
"B"
$PN"2"41;
%"UNIVERSAL_GND"
"1","(325,2300)","0","logical_power","I25";
;
HDL_POWER"GND"
CDS_LIB"logical_power";
"A"29;
%"Q_RES"
"2","(-175,2550)","0","pure_quanta","I26";
;
WATTAGE"1/16W"
MATERIAL"CHIP"
PART_NUMBER"CS41002FB09"
PACK_TYPE"0402LF"
VALUE"100K"
TOLERANCE"1%"
CDS_LIB"pure_quanta"
LOCATION"R314"
$SEC"1"
CDS_SEC"1";
"A"
$PN"1"41;
"B"
$PN"2"25;
%"UNIVERSAL_GND"
"1","(-175,2300)","0","logical_power","I27";
;
HDL_POWER"GND"
CDS_LIB"logical_power";
"A"25;
%"Q_DIODE"
"1","(-1400,2775)","0","pure_quanta","I28";
;
PART_NUMBER"BC000340033"
PACK_TYPE"SMLF"
MATERIAL"IC"
VALUE"SDMK0340L-7-F"
CDS_LIB"pure_quanta"
NEEDS_NO_SIZE"TRUE"
PIN_NAMES_ROTATE"True"
LOCATION"D17"
$SEC"1"
CDS_SEC"1";
"1"
$PN"1"40;
"2"
$PN"2"42;
%"UNIVERSAL_GND"
"1","(-575,3825)","0","logical_power","I3";
;
CDS_LIB"logical_power"
HDL_POWER"GND";
"A"17;
%"Q_RES"
"2","(-975,2600)","0","pure_quanta","I30";
;
TOLERANCE"1%"
WATTAGE"1/16W"
PART_NUMBER"CS44702FB02"
MATERIAL"CHIP"
PACK_TYPE"0402LF"
VALUE"470K"
CDS_LIB"pure_quanta"
LOCATION"R313"
$SEC"1"
CDS_SEC"1";
"A"
$PN"1"42;
"B"
$PN"2"26;
%"UNIVERSAL_GND"
"1","(-975,2350)","0","logical_power","I31";
;
CDS_LIB"logical_power"
HDL_POWER"GND";
"A"26;
%"UNIVERSAL_GND"
"1","(2400,1825)","0","logical_power","I34";
;
CDS_LIB"logical_power"
HDL_POWER"GND";
"A"18;
%"Q_RES"
"2","(-2000,725)","0","pure_quanta","I35";
;
PART_NUMBER"CS41002FB09"
VALUE"100K"
PACK_TYPE"0402LF"
MATERIAL"CHIP"
TOLERANCE"1%"
WATTAGE"1/16W"
CDS_LIB"pure_quanta"
LOCATION"R614"
$SEC"1"
CDS_SEC"1";
"A"
$PN"1"36;
"B"
$PN"2"14;
%"UNIVERSAL_GND"
"1","(-2000,475)","0","logical_power","I36";
;
CDS_LIB"logical_power"
HDL_POWER"GND";
"A"14;
%"MMBT39047F"
"1","(275,3750)","2","pure_quanta","I4";
;
VALUE"MMBT3904-7-F"
PART_NUMBER"BA0390400H0"
PART_TYPE"SMLF"
MATERIAL"IC"
SEC_TYPE""
CDS_LMAN_SYM_OUTLINE"-50,50,50,-50"
NEEDS_NO_SIZE"TRUE"
CDS_LIB"pure_quanta"
LOCATION"Q3"
SEC"1";
"3"
$PN"C"49;
"2"
$PN"E"24;
"1"
$PN"B"33;
%"Q_RES"
"1","(450,1100)","0","pure_quanta","I41";
;
MATERIAL"CHIP"
VALUE"49.9"
CDS_LIB"pure_quanta"
WATTAGE"1/16W"
PACK_TYPE"0402LF"
PART_NUMBER"CS04992FB07"
TOLERANCE"1%"
LOCATION"R192"
$SEC"1"
CDS_SEC"1";
"B"
$PN"2"31;
"A"
$PN"1"34;
%"Q_CAP"
"1","(-675,1650)","0","pure_quanta","I42";
;
VALUE"0.1UF"
VOLTAGE"25V"
PART_NUMBER"CH4104K1B00"
PACK_TYPE"0402"
MATERIAL"X7R"
TOLERANCE"10%"
CDS_LIB"pure_quanta"
LOCATION"C34"
$SEC"1"
CDS_SEC"1";
"B"
$PN"2"16;
"A"
$PN"1"11;
%"UNIVERSAL_GND"
"1","(-675,1425)","0","logical_power","I43";
;
CDS_LIB"logical_power"
HDL_POWER"GND";
"A"16;
%"UNIVERSAL_POWER"
"1","(-875,1925)","0","logical_power","I44";
;
HDL_POWER"P3V3_AUX"
CDS_LIB"logical_power";
"A"11;
%"UNIVERSAL_GND"
"1","(1275,575)","0","logical_power","I45";
;
HDL_POWER"GND"
CDS_LIB"logical_power";
"A"22;
%"Q_CAP"
"1","(1275,775)","0","pure_quanta","I46";
;
VALUE"4700P"
PART_NUMBER"CH2474K1B08"
MATERIAL"EMPTY"
TOLERANCE"10%"
VOLTAGE"25V"
PACK_TYPE"C0402"
CDS_LIB"pure_quanta"
LOCATION"C223"
$SEC"1"
CDS_SEC"1";
"B"
$PN"2"22;
"A"
$PN"1"31;
%"UNIVERSAL_GND"
"1","(-1725,750)","0","logical_power","I48";
;
CDS_LIB"logical_power"
HDL_POWER"GND";
"A"15;
%"Q_RES"
"1","(-2425,1800)","0","pure_quanta","I49";
;
TOLERANCE"5%"
WATTAGE"1/16W"
VALUE"0"
PACK_TYPE"0402LF"
MATERIAL"EMPTY"
CDS_LIB"pure_quanta"
PART_NUMBER"CS00002JB13"
LOCATION"R711"
$SEC"1"
CDS_SEC"1";
"B"
$PN"2"37;
"A"
$PN"1"46;
%"Q_RES"
"2","(-575,4400)","0","pure_quanta","I5";
;
VALUE"499"
TOLERANCE"1%"
WATTAGE"1/16W"
MATERIAL"CHIP"
PACK_TYPE"0402LF"
PART_NUMBER"CS14992FB06"
CDS_LIB"pure_quanta"
LOCATION"R287"
$SEC"1"
CDS_SEC"1";
"A"
$PN"1"8;
"B"
$PN"2"52;
%"VCCAUX15"
"1","(-400,675)","0","logical_power","I53";
;
HDL_POWER"P1V0_AUX"
CDS_LIB"logical_power";
"A"13;
%"UNIVERSAL_POWER"
"1","(-250,425)","0","logical_power","I54";
;
HDL_POWER"P3V3_AUX"
CDS_LIB"logical_power";
"A"7;
%"Q_RES"
"2","(-250,0)","0","pure_quanta","I55";
;
PART_NUMBER"CS41002FB09"
PACK_TYPE"0402LF"
VALUE"100K"
MATERIAL"CHIP"
WATTAGE"1/16W"
TOLERANCE"1%"
CDS_LIB"pure_quanta"
LOCATION"R710"
$SEC"1"
CDS_SEC"1";
"A"
$PN"1"7;
"B"
$PN"2"30;
%"UNIVERSAL_POWER"
"1","(-550,475)","0","logical_power","I56";
;
HDL_POWER"P3V3_AUX"
CDS_LIB"logical_power";
"A"1;
%"Q_CAP"
"1","(-875,225)","0","pure_quanta","I57";
;
VOLTAGE"25V"
VALUE"0.1UF"
TOLERANCE"10%"
MATERIAL"X7R"
PACK_TYPE"0402"
PART_NUMBER"CH4104K1B00"
CDS_LIB"pure_quanta"
LOCATION"C253"
$SEC"1"
CDS_SEC"1";
"B"
$PN"2"19;
"A"
$PN"1"1;
%"UNIVERSAL_GND"
"1","(-875,0)","0","logical_power","I58";
;
CDS_LIB"logical_power"
HDL_POWER"GND";
"A"19;
%"Q_CAP"
"1","(-250,-425)","0","pure_quanta","I59";
;
PART_NUMBER"CH4104K1B00"
VALUE"0.1UF"
TOLERANCE"10%"
MATERIAL"X7R"
PACK_TYPE"0402"
VOLTAGE"25V"
CDS_LIB"pure_quanta"
LOCATION"C264"
$SEC"1"
CDS_SEC"1";
"B"
$PN"2"21;
"A"
$PN"1"30;
%"UNIVERSAL_GND"
"1","(225,3350)","0","logical_power","I6";
;
CDS_LIB"logical_power"
HDL_POWER"GND";
"A"24;
%"UNIVERSAL_GND"
"1","(-1550,-725)","0","logical_power","I61";
;
HDL_POWER"GND"
CDS_LIB"logical_power";
"A"21;
%"Q_RES"
"1","(450,1000)","0","pure_quanta","I65";
;
PACK_TYPE"0402LF"
MATERIAL"CHIP"
TOLERANCE"1%"
PART_NUMBER"CS04992FB07"
WATTAGE"1/16W"
VALUE"49.9"
CDS_LIB"pure_quanta"
LOCATION"R108"
$SEC"1"
CDS_SEC"1";
"B"
$PN"2"31;
"A"
$PN"1"35;
%"UNIVERSAL_POWER"
"1","(1275,2850)","0","logical_power","I66";
;
HDL_POWER"P3V3_AUX"
CDS_LIB"logical_power";
"A"9;
%"Q_RES"
"2","(1275,2525)","0","pure_quanta","I67";
;
PACK_TYPE"0402LF"
PART_NUMBER"CS22002FB07"
WATTAGE"1/16W"
TOLERANCE"1%"
MATERIAL"CHIP"
VALUE"2K"
CDS_LIB"pure_quanta"
LOCATION"R124"
$SEC"1"
CDS_SEC"1";
"A"
$PN"1"9;
"B"
$PN"2"31;
%"Q_RES"
"1","(3075,1425)","0","pure_quanta","I69";
;
PART_NUMBER"CS11002FB07"
MATERIAL"CHIP"
PACK_TYPE"0402LF"
WATTAGE"1/16W"
TOLERANCE"1%"
VALUE"100"
CDS_LIB"pure_quanta"
LOCATION"R125"
$SEC"1"
CDS_SEC"1";
"B"
$PN"2"51;
"A"
$PN"1"31;
%"Q_RES"
"2","(225,4400)","0","pure_quanta","I7";
;
PACK_TYPE"0402LF"
PART_NUMBER"CS31002FB08"
TOLERANCE"1%"
WATTAGE"1/16W"
MATERIAL"CHIP"
VALUE"10K"
CDS_LIB"pure_quanta"
LOCATION"R289"
$SEC"1"
CDS_SEC"1";
"A"
$PN"1"4;
"B"
$PN"2"49;
%"Q_RES"
"1","(1550,2125)","0","pure_quanta","I71";
;
WATTAGE"1/16W"
PART_NUMBER"CS00002JB13"
PACK_TYPE"0402LF"
MATERIAL"EMPTY"
TOLERANCE"5%"
VALUE"0"
CDS_LIB"pure_quanta"
LOCATION"R315"
$SEC"1"
CDS_SEC"1";
"B"
$PN"2"56;
"A"
$PN"1"31;
%"Q_RES"
"1","(-2975,-275)","0","pure_quanta","I72";
;
WATTAGE"1/16W"
VALUE"0"
PACK_TYPE"0402LF"
MATERIAL"CHIP"
TOLERANCE"5%"
CDS_LIB"pure_quanta"
PART_NUMBER"CS00002JB13"
LOCATION"R49"
$SEC"1"
CDS_SEC"1";
"B"
$PN"2"48;
"A"
$PN"1"54;
%"Q_RES"
"1","(-2975,-175)","0","pure_quanta","I74";
;
MATERIAL"CHIP"
VALUE"0"
PART_NUMBER"CS00002JB13"
CDS_LIB"pure_quanta"
TOLERANCE"5%"
WATTAGE"1/16W"
PACK_TYPE"0402LF"
LOCATION"R451"
$SEC"1"
CDS_SEC"1";
"B"
$PN"2"47;
"A"
$PN"1"53;
%"Q_RES"
"1","(3225,3750)","0","pure_quanta","I8";
;
WATTAGE"1/16W"
VALUE"47K"
TOLERANCE"1%"
MATERIAL"CHIP"
PACK_TYPE"0402LF"
PART_NUMBER"CS34702FB01"
CDS_LIB"pure_quanta"
LOCATION"R290"
$SEC"1"
CDS_SEC"1";
"B"
$PN"2"32;
"A"
$PN"1"33;
%"UNIVERSAL_POWER"
"1","(-1725,3250)","0","logical_power","I80";
;
HDL_POWER"P3V3_AUX"
CDS_LIB"logical_power";
"A"3;
%"Q_RES"
"2","(-1725,3050)","0","pure_quanta","I81";
;
PACK_TYPE"0402LF"
VALUE"1K"
WATTAGE"1/16W"
TOLERANCE"1%"
MATERIAL"EMPTY"
CDS_LIB"pure_quanta"
SEC_TYPE"0402LF"
PART_NUMBER"CS21002FB06"
LOCATION"R633"
SEC"1";
"A"
$PN"1"3;
"B"
$PN"2"40;
%"UNIVERSAL_POWER"
"1","(-2600,525)","0","logical_power","I82";
;
HDL_POWER"P3V3_AUX"
CDS_LIB"logical_power";
"A"6;
%"Q_RES"
"2","(-2600,200)","0","pure_quanta","I83";
;
PACK_TYPE"0402LF"
PART_NUMBER"CS22002FB07"
MATERIAL"CHIP"
WATTAGE"1/16W"
VALUE"2K"
TOLERANCE"1%"
CDS_LIB"pure_quanta"
LOCATION"R751"
$SEC"1"
CDS_SEC"1";
"A"
$PN"1"6;
"B"
$PN"2"47;
%"UNIVERSAL_POWER"
"1","(-575,4700)","0","logical_power","I84";
;
HDL_POWER"P3V3_RGM"
CDS_LIB"logical_power";
"A"8;
%"UNIVERSAL_POWER"
"1","(225,4825)","0","logical_power","I85";
;
HDL_POWER"P3V3_RGM"
CDS_LIB"logical_power";
"A"4;
%"74LVC2G07DW7"
"1","(-1275,1050)","0","pure_quanta","I87";
;
VALUE"74LVC2G07DW-7"
PART_NUMBER"AL002G07003"
MATERIAL"IC"
PART_TYPE"SMLF"
CDS_LMAN_SYM_OUTLINE"-175,100,175,-100"
NEEDS_NO_SIZE"TRUE"
CDS_LIB"pure_quanta"
LOCATION"U6"
$SEC"1"
CDS_SEC"1";
"VCC"
$PN"5"11;
"GND"
$PN"2"15;
"2Y"
$PN"4"35;
"1Y"
$PN"6"34;
"2A"
$PN"3"36;
"1A"
$PN"1"37;
%"MC74VHC1G07DFT2G"
"1","(3125,2125)","0","pure_quanta","I89";
;
MATERIAL"EMPTY"
PART_TYPE"SMLF"
PART_NUMBER"AL001G07003"
VALUE"MC74VHC1G07DFT2G"
CDS_LIB"pure_quanta"
NEEDS_NO_SIZE"TRUE"
CDS_LMAN_SYM_OUTLINE"-350,150,350,-150"
LOCATION"U13"
$SEC"1"
CDS_SEC"1";
"NC1"
$PN"1"0;
"OUT_Y"
$PN"4"32;
"GND"
$PN"3"18;
"IN_A"
$PN"2"56;
"VCC"
$PN"5"5;
%"Q_RES"
"2","(4000,4050)","0","pure_quanta","I9";
;
VALUE"4.7K"
TOLERANCE"1%"
WATTAGE"1/16W"
MATERIAL"CHIP"
PACK_TYPE"0402LF"
PART_NUMBER"CS24702FB06"
CDS_LIB"pure_quanta"
LOCATION"R291"
$SEC"1"
CDS_SEC"1";
"A"
$PN"1"4;
"B"
$PN"2"32;
%"TPS3808G18DBVR"
"1","(-1125,-225)","0","pure_quanta","I90";
;
VALUE"TPS3808G01DBVR"
PART_NUMBER"AL003808005"
PART_TYPE"SMLF"
MATERIAL"IC"
CDS_LMAN_SYM_OUTLINE"-200,100,200,-100"
NEEDS_NO_SIZE"TRUE"
CDS_LIB"pure_quanta"
LOCATION"U43"
$SEC"1"
CDS_SEC"1";
"SENSE"
$PN"5"13;
"CT"
$PN"4"30;
"VDD"
$PN"6"1;
"#MR \B"
$PN"3"48;
"GND"
$PN"2"21;
"#RESET \B"
$PN"1"47;
%"Q_RES"
"1","(-3075,1000)","0","pure_quanta","I92";
;
VALUE"33.2"
MATERIAL"CHIP"
PACK_TYPE"0402LF"
WATTAGE"1/16W"
PART_NUMBER"CS03322FB03"
TOLERANCE"1%"
CDS_LIB"pure_quanta"
$LOCATION"R388"
CDS_LOCATION"R388"
$SEC"1"
CDS_SEC"1";
"B"
$PN"2"36;
"A"
$PN"1"45;
%"MC74VHC1G32DTT1G"
"1","(-2475,2475)","0","pure_quanta","I94";
;
PART_NUMBER"AL001G32031"
MATERIAL"IC"
PART_TYPE"SMLF"
VALUE"MC74VHC1G32DTT1G"
CDS_LIB"pure_quanta"
CDS_LMAN_SYM_OUTLINE"-400,275,400,-275"
NEEDS_NO_SIZE"TRUE"
$LOCATION"U58"
CDS_LOCATION"U58"
$SEC"1"
CDS_SEC"1";
"VCC"
$PN"5"10;
"GND"
$PN"3"28;
"IN_A"
$PN"2"39;
"IN_B"
$PN"1"44;
"OUT_Y"
$PN"4"40;
%"UNIVERSAL_GND"
"1","(-3025,2150)","0","logical_power","I95";
;
HDL_POWER"GND"
CDS_LIB"logical_power";
"A"28;
%"UNIVERSAL_GND"
"1","(-2050,2900)","0","logical_power","I96";
;
HDL_POWER"GND"
CDS_LIB"logical_power";
"A"27;
%"Q_CAP"
"1","(-2050,3125)","2","pure_quanta","I97";
;
TOLERANCE"10%"
PACK_TYPE"0402"
VALUE"0.1UF"
MATERIAL"X7R"
PART_NUMBER"CH4104K1B00"
VOLTAGE"25V"
CDS_LIB"pure_quanta"
$LOCATION"C337"
CDS_LOCATION"C337"
$SEC"1"
CDS_SEC"1";
"B"
$PN"2"27;
"A"
$PN"1"10;
%"VCCAUX15"
"1","(-2050,3375)","0","logical_power","I98";
;
HDL_POWER"P3V3_AUX"
CDS_LIB"logical_power";
"A"10;
END.
